  
  1 
OCP Accelerator Module Design Specification v1.0 
 
 
 
OCP Accelerator Module Design 
Specification v1.0 
Author: 
Whitney Zhao, Hardware Engineer, Facebook 
Tiffany Jin, Mechanical Engineer, Facebook 
Cheng Chen, Thermal Engineer, Facebook 
Siamak Tavallaei, Principal Architect, Microsoft 
Zhenghui Wu, Staff System Engineer, Baidu 


  
  2 
OCP Accelerator Module Design Specification v1.0 
 
1 Contents 
2 License ................................................................................................................................................... 5 
3 Acknowledge ......................................................................................................................................... 6 
4 Overview ............................................................................................................................................... 7 
4.1 Scope ............................................................................................................................................. 8 
4.2 Acronyms ...................................................................................................................................... 8 
5 High Level Specification for the OCP Acceleration Module .................................................................. 9 
6 Accelerator Module Mechanical Specifications .................................................................................. 10 
6.1 Module PCBA Form Factor .......................................................................................................... 10 
6.2 Mezzanine Connector ................................................................................................................. 13 
6.2.1 Mate/Unmate Force Data ................................................................................................... 14 
6.3 Accelerator Module Top Stiffener .............................................................................................. 15 
6.4 Accelerator Module Bottom Stiffener ........................................................................................ 15 
6.4.1 Tolerance Stack-up of Bottom Stiffener ............................................................................. 18 
6.4.2 Alignment Pins .................................................................................................................... 18 
6.4.3 EMI Gaskets / Pads .............................................................................................................. 19 
6.4.4 Die Springs........................................................................................................................... 20 
6.5 Baseboard Keepout Zone & Grounding Pads.............................................................................. 22 
6.5.1 SMT Nut .............................................................................................................................. 23 
6.5.2 Component Keep-out Zone ................................................................................................. 23 
6.5.3 Grounding Pads ................................................................................................................... 23 
6.6 Recommended Alignment Features ........................................................................................... 23 
6.7 Reference Heatsink Design ......................................................................................................... 25 
6.7.1 Top Handle .......................................................................................................................... 25 
6.7.2 Long Screw Attachment ...................................................................................................... 26 
7 Thermal Specification ......................................................................................................................... 27 
7.1 Environmental Conditions .......................................................................................................... 27 
7.2 Temperature Report ................................................................................................................... 28 
7.2.1 Temperature Sensors .......................................................................................................... 28 
7.2.2 Remaining Components ...................................................................................................... 28 
7.3 Thermal module info ................................................................................................................... 28 



  
  3 
OCP Accelerator Module Design Specification v1.0 
 
7.4 Heatsink Assembly ...................................................................................................................... 28 
7.5 Thermal Recommendation ......................................................................................................... 29 
7.5.1 Airflow Budget .................................................................................................................... 29 
7.5.2 Reference Heatsink Design ................................................................................................. 29 
7.5.3 Cooling Limit ....................................................................................................................... 31 
7.5.4 Heatsink Installation ........................................................................................................... 33 
7.5.5 Thermal Interface Material ................................................................................................. 34 
8 Accelerator Module Electrical Specification ....................................................................................... 36 
8.1 Electrical Connector .................................................................................................................... 36 
8.2 Mezzanine Module Connector Pinout Quadrants ...................................................................... 37 
8.3 Accelerator Module Pinout Description ..................................................................................... 38 
8.4 Accelerator Module Power Profiles ............................................................................................ 47 
8.4.1 Thermal Design Power TDP ................................................................................................. 47 
8.4.2 Excursion Design Power EDP ............................................................................................... 48 
8.5 System power sequencing .......................................................................................................... 48 
8.6 Mezzanine Module Insertion Loss .............................................................................................. 50 
8.7 Management link ........................................................................................................................ 51 
9 Mezzanine Module Interconnect Topologies ..................................................................................... 52 
9.1 Module ID.................................................................................................................................... 52 
9.2 Interconnect Topology ................................................................................................................ 53 
9.2.1 Hybrid Cube Mesh (HCM) for 6 ports per OAM .................................................................. 53 
9.2.2 Almost Fully Connected ...................................................................................................... 54 
9.2.3 Hybrid Cube Mesh for 8 ports per OAM ............................................................................. 55 
9.2.4 Fully Connected ................................................................................................................... 56 
9.2.5 Combined FC/HCM Topology .............................................................................................. 57 
9.2.6 4D Hypercube...................................................................................................................... 58 
9.3 LINK_CONFIG[4:0] ....................................................................................................................... 59 
9.4 Accelerator Interconnect PCB Topology ..................................................................................... 60 
10 Mezzanine module reference system design ................................................................................. 61 
11 System Level Communication ......................................................................................................... 62 
11.1 Sideband Management Interface ............................................................................................... 62 



  
  4 
OCP Accelerator Module Design Specification v1.0 
 
11.2 Sensor Reporting ......................................................................................................................... 62 
11.3 Error Monitoring/Reporting ........................................................................................................ 63 
11.4 Firmware Update ........................................................................................................................ 63 
11.5 Power Capping ............................................................................................................................ 63 
11.6 FRU Information .......................................................................................................................... 63 
11.7 IO Calibration .............................................................................................................................. 63 
12 Environmental ................................................................................................................................. 65 
12.1 Environmental Requirements ..................................................................................................... 65 
12.2 Regulation ................................................................................................................................... 65 
13 Revision History .............................................................................................................................. 66 
 



  
  5 
OCP Accelerator Module Design Specification v1.0 
 
2 License 
Contributions to this Specification are made under the terms and conditions set forth in Open Web Foundation Contributor 
License Agreement (“OWF CLA 1.0”) (“Contribution License”) by:  
Facebook Inc. 
Microsoft Corporation. 
Beijing Baidu Netcom Science Technology Co., Ltd 
 
Usage of this Specification is governed by the terms and conditions set forth in the Open Web Foundation Final Specification 
Agreement (“OWFa 1.0”). 
 
Note:  The following clarifications, which distinguish technology licensed in the Contribution License and/or Specification 
License from those technologies merely referenced (but not licensed), were accepted by the Incubation Committee of the OCP:   
None. 
 
NOTWITHSTANDING THE FOREGOING LICENSES, THIS SPECIFICATION IS PROVIDED BY OCP "AS IS" AND OCP EXPRESSLY 
DISCLAIMS ANY WARRANTIES (EXPRESS, IMPLIED, OR OTHERWISE), INCLUDING IMPLIED WARRANTIES OF MERCHANTABILITY, 
NON-INFRINGEMENT, FITNESS FOR A PARTICULAR PURPOSE, OR TITLE, RELATED TO THE SPECIFICATION. NOTICE IS HEREBY 
GIVEN, THAT OTHER RIGHTS NOT GRANTED AS SET FORTH ABOVE, INCLUDING WITHOUT LIMITATION, RIGHTS OF THIRD 
PARTIES WHO DID NOT EXECUTE THE ABOVE LICENSES, MAY BE IMPLICATED BY THE IMPLEMENTATION OF OR COMPLIANCE 
WITH THIS SPECIFICATION. OCP IS NOT RESPONSIBLE FOR IDENTIFYING RIGHTS FOR WHICH A LICENSE MAY BE REQUIRED IN 
ORDER TO IMPLEMENT THIS SPECIFICATION.  THE ENTIRE RISK AS TO IMPLEMENTING OR OTHERWISE USING THE 
SPECIFICATION IS ASSUMED BY YOU. IN NO EVENT WILL OCP BE LIABLE TO YOU FOR ANY MONETARY DAMAGES WITH RESPECT 
TO ANY CLAIMS RELATED TO, OR ARISING OUT OF YOUR USE OF THIS SPECIFICATION, INCLUDING BUT NOT LIMITED TO ANY 
LIABILITY FOR LOST PROFITS OR ANY CONSEQUENTIAL, INCIDENTAL, INDIRECT, SPECIAL OR PUNITIVE DAMAGES OF ANY 
CHARACTER FROM ANY CAUSES OF ACTION OF ANY KIND WITH RESPECT TO THIS SPECIFICATION, WHETHER BASED ON BREACH 
OF CONTRACT, TORT (INCLUDING NEGLIGENCE), OR OTHERWISE, AND EVEN IF OCP HAS BEEN ADVISED OF THE POSSIBILITY OF 
SUCH DAMAGE. 
 
 



  
  6 
OCP Accelerator Module Design Specification v1.0 
 
3 Acknowledge  
We would like to acknowledge Intel Corporation and Advanced Micro Devices(AMD), Inc. for their 
collaboration on the engineering analysis for the OCP accelerator module specification development, 
including physical form factor, logical connectivity, signal breakout and routing studies, signal integrity 
analysis, and power delivery analysis. 
A special acknowledgement to Molex LLC for their cross-functional support as it pertains to the Mirror 
Mezz connector and its implementation into this module specification. 
We also want to acknowledge the community’s great support for specification. After we first time talked 
the common form factor accelerator module during the OCP server group monthly call and HPC group 
monthly call in November 2018, we got a lot great feedback from the community, for us to enhance the 
specification can be adopted by wider community.  
 



  
  7 
OCP Accelerator Module Design Specification v1.0 
 
4 Overview 
Artificial Intelligence (AI) applications are rapidly evolving and producing an explosion of new types of 
hardware accelerators for Machine Learning (ML), Deep Learning (DL), and High-performance 
Computing (HPC).   
Different implementations target similar requirements for power/cooling, robustness, serviceability, 
configuration, programming, management, debug, inter-module communication to scale-up, and 
input/output bandwidth to scale-out. 
To take advantage of the available industry-standard form factors to reduce the required time and effort 
in producing suitable solutions, various implementations have selected PCIe CEM form factor as a quick 
market entry.  
Such solutions are not optimized for the upcoming AI workloads which require ever-growing bandwidth 
and interconnect flexibility for data/model parallelism.  
The state-of-the-art applications require multiple cards in a system with multiple inter-card links running 
at highspeed interconnect bandwidth between cards.   
Using PCIe CEM form factor to meet such interconnect requirement poses several challenges such as 
excessive signal insertion loss from ASIC to PCIe connectors and on baseboard; inter-card cabling 
complexity reducing robustness and serviceability; and limits the supported inter-ASIC topologies. 
To enable flexible high-speed interconnect topologies for multi-ASIC solutions, this base specification 
outlines an interoperable, modular hierarchy based on a mezzanine module form factor (OCP 
Accelerator Module: OAM), an interconnect Baseboard, a Tray, and a Chassis. 
 Mezzanine Module (various accelerators) 
 Baseboard (interconnecting topologies between accelerators, hosts, and other IO devices to 
scale up) 
 Tray (a means for ease of field replacement and serviceability) 
 Chassis (an outline for a collection of Trays and input/output resources to scale out) 
Based on this base specification, various design and product implementations may maintain 
interoperability while offering enhancements in each hierarchy level. 
We invite open contributions in the following areas:  
1. Base specification (OCP Accelerator Infrastructure Project Specification) 
2. Design specification (This document, detailed description of alternative, interoperable 
components which meet the base specification) 
3. Products (schematic, layout, mechanical/thermal solutions, and firmware/software to realize 
the above designs) 
 



  
  8 
OCP Accelerator Module Design Specification v1.0 
 
4.1 Scope 
The OCP Accelerator Mezzanine Module design specification defines the form factor and common 
specifications for a compute accelerator module and a compliant base board design enabling 
interoperability across multiple ASIC or GPU based mezzanine modules and a based board design 
interface.  
The mezzanine module form factor facilitates scalability across accelerators by simplifying the system 
solution when interconnecting communication links among modules in comparison with a PCIe Add-in 
card form factor. 
4.2 Acronyms 
Acronym Definition  
ASIC Application Specific Integrated Circuit 
OAM OCP Accelerator Module 
BGA Ball Grid Array 
BMC Baseboard Management Controller 
TDP Thermal Design Power 
EDP Excursion Design Power 
GPU Graphic Processing Unit 
MPN Manufacturing Part Number 
DXF Drawing eXchange Format 
PCBA Printed Circuit Board Assembly 
 
 
 



  
  9 
OCP Accelerator Module Design Specification v1.0 
 
5 High Level Specification for the OCP Acceleration Module 
 
 
 
 
 
Module Dimension 102mm x 165mm 
Board Thickness  1.57 - 3.20mm ± 10% 
Module Power/Input 
Voltage  
o High power module supports up to 700W, using 44V-59.5V DC 
as input power 
o Low power module supports up to 350W, using 11-13.2V DC as 
input power 
Connectors  
2* Molex Mirror Mezz Connectors (MPN: 209311-1115) 
Stack height 5mm 
Differential pair Impedance: 90ohm ± 5% 
Host Interface One or two x16 host link. E.g. PCIe Gen3/4/5 x16, or alternate 
protocols. 
Module to Module 
Interconnect Links 
Up to 7 Links per module, each link has up to X16-X20 lanes 
Each link may be able to be configured to sub links.  
Bottom stiffener height 
(including Mylar) 5 ± 0.15mm 
 



  
  10 
OCP Accelerator Module Design Specification v1.0 
 
6 Accelerator Module Mechanical Specifications 
The accelerator module form factor is described in this section. It uses a single accelerator ASIC on the 
module as an example to describe the mechanical specifications. The top and bottom stiffeners may be 
different if the modules have multiple accelerator ASICs.  
Please refer to 2D DXF and 3D files for further details. 2D DXF and 3D files are included with the 
contribution package as well as relevant reference drawings to mechanical components. Please note 
that some features on the OAM are called out as required, but others are included merely for reference. 
 
 
 
 
 
 
 
 
 
 
 
 
Figure 1 OCP Accelerator Module isometric view 
6.1 Module PCBA Form Factor 
This section covers the required and recommended dimensions of the module PCBA and its individual 
parts. Figures 2 and 3 illustrate Mezzanine form factor and dimensions, with all the dimensions in Figure 
2 required. It is a 102mm x 165mm PCB size with Mezzanine Connectors on the bottom side and 
Accelerator on top side. Connector to connector pitch is 102mm. Four NPTH mounting holes are used to 
attach the module to a corresponding bolster plate secured below the system PCB. These mounting 
holes should provide clearance for a M3.5 screw, with enough thread length to secure to the bottom 
stiffener. There is a notch located near the southwest corner of the board, adjacent to Connector 1. For 
connector orientation, see Figure 4 Top and bottom views of the Accelerator Module Assembly. 
 
Top stiffener 
Bottom stiffener 
Example die 
OAM PCB 



  
  11 
OCP Accelerator Module Design Specification v1.0 
 
 
Figure 2 102mm wide OCP Accelerator Module Form Factor Dimensions, Bottom View 
 
 


  
  12 
OCP Accelerator Module Design Specification v1.0 
 
 
Figure 3 OCP Accelerator Module Form Factor, Side View with System Baseboard 
 
 
Figure 4 Top and bottom views of the Accelerator Module Assembly 
  


  
  13 
OCP Accelerator Module Design Specification v1.0 
 
6.2 Mezzanine Connector 
Molex Mirror Mezz (MPN: 209311-1115) is the PCB to PCB interconnect solution supported by the OCP 
Accelerator Module form factor. Mirror Mezz is a highspeed differential pair-based mezzanine 
connector in a footprint-identical genderless plug and receptacle part for module and base board. Figure 
5 Mirror Mezz 209311-1115 is provided courtesy of Molex. 
o Stack Height: 5mm 
o Mating Force: 0.35N/pin Max, total 240.8N MAX. Data on mate forces of the 209311-1115 
connector is shown in Table 1 Mate/Unmate Averaged Data for Molex Mirror Mezz 209311-
1115. 
o Unmating force: 0.045N/pin MIN, total 31.0N MIN. Data on unmate forces of the 209311-1115 
connector is shown in Table 1 Mate/Unmate Averaged Data for Molex Mirror Mezz 209311-
1115. 
o Weight of OAM + Heatsink: 2kg MAX 
o 172 Total Differential Pairs, of which 161 are fully ground shielded (non-orphan) 
 
Figure 5 Mirror Mezz 209311-1115 
 
  


  
  14 
OCP Accelerator Module Design Specification v1.0 
 
6.2.1 Mate/Unmate Force Data 
The mating connectors will be vertically inverted when mated.  
 
Figure 6 Mirror Mezz Connector Mating 
The mate and unmate forces provided in the product specification are conservative. The specific 
209311-1115 connector that the OAM uses has mate/unmate forces more in line with those found in 
Table 1 Mate/Unmate Averaged Data for Molex Mirror Mezz 209311-1115 and in Figure 7 Measured 
Mate Force per Pin for Molex Mirror Mezz 209311-1115. Note that the mate force per pin trends 
upwards for initial 5 cycles before settling back towards the average of 0.21N/pin.  
Table 1 Mate/Unmate Averaged Data for Molex Mirror Mezz 209311-1115 
 


  
  15 
OCP Accelerator Module Design Specification v1.0 
 
 
 
Figure 7 Measured Mate Force per Pin for Molex Mirror Mezz 209311-1115 
6.3 Accelerator Module Top Stiffener 
The reference model for the accelerator mezzanine module top stiffener is purely reference and 
dimensions may be changed or adjusted to accommodate the specific application and board layout of 
the OAM PCB. 
6.4 Accelerator Module Bottom Stiffener 
The reference model for the accelerator mezzanine module bottom stiffener is shown in Figure 8 
Reference Design of Bottom Stiffener. Required dimensions are shown in Figure 9 Bottom Stiffener 
Required Dimensions. Note that the bottom stiffener must accommodate the SMT nuts of dimensions 
shown in Figure 15 SMT Receiving Nut for Baseboard. Other features and dimensions of the bottom 
stiffener shown in the reference model are optional and can be adjusted based on the needs of the 
module PCB. 


  
  16 
OCP Accelerator Module Design Specification v1.0 
 
 
Figure 8 Reference Design of Bottom Stiffener 


  
  17 
OCP Accelerator Module Design Specification v1.0 
 
 
Figure 9 Bottom Stiffener Required Dimensions 
 
  


  
  18 
OCP Accelerator Module Design Specification v1.0 
 
6.4.1 Tolerance Stack-up of Bottom Stiffener 
Standoff height as recommended by Molex for the Mirror Mezzanine Connector is 5mm ± 0.15mm. This 
tolerance may be difficult to attain using an insulator-adhesive-stiffener-adhesive-insulator stack, so it is 
highly recommended that pockets be machined into the stiffener to account for the tolerances of the 
insulator and adhesive (see reference design CAD for further details). With a stiffener only stack, 
0.15mm should be easily attainable.  
 
Figure 10 Tolerance Stack-up of Bottom Stiffener 
6.4.2 Alignment Pins 
There are two alignment pins required on the bottom stiffener of the mezzanine module, intended as 
guidance features as well as an additional keying feature for the module (see Section 6.5 for more 
details). They are to be defined as 3mm diameter, with a length of 10mm measured from the bottom of 
the mezzanine PCB. Note that since there may be components on the bottom side of the PCB, if the 
stiffener is pocketed in this area the total length of the pin will be shorter than 10mm. It is 
recommended that the minimum thickness of the stiffener is 1mm in these areas. Figure 12 shows an 
example of a possible alignment pin. Note that the length will vary depending on the specific chosen 
geometry of the bottom stiffener.  
MPN: PEM TPS-3mm-8 or equivalent 


  
  19 
OCP Accelerator Module Design Specification v1.0 
 
 
Figure 11 Alignment pin example 
 
6.4.3 EMI Gaskets / Pads 
The bottom stiffener has two defined areas of 8x42mm size that are reserved for placement of fabric-
over-foam gaskets. This area is designed to have a 0.5mm depth, and the gasket defined should have a 
6x40mm footprint, with 1mm height. This provides a 50% nominal compression and solid grounding to 
the baseboard (which has an equivalently designed ground pad). 
MPN: Laird 4Y03PC51H00158 or equivalent 
 


  
  20 
OCP Accelerator Module Design Specification v1.0 
 
 
Figure 12 Fabric-over-foam Gasket Locations (brown) 
 
6.4.4 Die Springs 
Due to the large number of pins, the mate and unmate forces of the Molex Mirror Mezzanine 
connectors are high (see Section 6.2.1). To assist with the de-mate, die springs are to be used. It is 
strongly suggested for OAM vendors to use this reference spring in  
However, an equivalent spring shall have a spring constant of at least 70N/mm, and a compression of at 
least 2.5mm. Inner diameter shall be 4.2mm and outer diameter shall be 7.8mm. These springs fit into 
8mm diameter counterbores of 4mm depth in the bottom stiffener. Installation method is using glue 
(3M DP810 or equivalent), applied with maximum thickness of 0.1mm. 
MPN: Timson WG774265 or equivalent 


  
  21 
OCP Accelerator Module Design Specification v1.0 
 
 
 
 
D (mm) d (mm) L (mm) a (mm) F (mm) K (N/mm) 
𝟕.𝟖ି𝟎.𝟐𝟎ା𝟎.𝟎𝟓 4.2ି଴.ଵହା଴.ଵ  6.5ି଴.ଶା଴.ଶ 3.6ି଴.ଵହା଴.ଵହ 2.9ି଴.ଷହା଴.ଷହ 78.6±10% 
Figure 13 Die Spring dimensions and drawing 
 
Table 2 Spring constant and free length of die springs, shown compared to cycle count 
 Sample 1 Sample 2 Sample 3 Sample 4 Sample 5 
L 
(mm) 
K 
(N/mm) 
L 
(mm) 
K 
(N/mm) 
L 
(mm) 
K 
(N/mm) 
L 
(mm) 
K 
(N/mm) 
L 
(mm) 
K 
(N/mm) 
1 6.48 81.87 6.44 80.88 6.48 82.12 6.45 80.20 6.46 80.70 
2 6.47 81.23 6.43 79.80 6.47 81.86 6.44 79.98 6.46 80.58 
3 6.47 81.01 6.42 79.84 6.47 81.33 6.44 79.96 6.45 80.48 
4 6.46 80.95 6.42 79.70 6.46 81.20 6.44 79.80 6.45 80.46 
5 6.46 80.95 6.41 79.37 6.46 81.17 6.43 79.68 6.44 80.28 
6 6.46 80.90 6.41 79.22 6.46 81.13 6.43 79.40 6.44 80.29 
7 6.46 80.79 6.40 79.31 6.45 80.97 6.42 79.52 6.43 80.12 
8 6.45 80.77 6.40 79.16 6.45 81.17 6.42 79.48 6.43 80.02 
9 6.45 80.76 6.39 79.11 6.43 80.98 6.41 79.47 6.42 79.90 
10 6.44 80.68 6.39 79.02 6.43 80.91 6.41 79.38 6.42 79.93 
Avg 6.46 80.99 6.41 79.54 6.46 81.28 6.43 79.69 6.44 80.28 
  


  
  22 
OCP Accelerator Module Design Specification v1.0 
 
6.5 Baseboard Keepout Zone & Grounding Pads 
The below figure shows the baseboard outline (top side view) required to accommodate this module. All 
cross-hatched areas are required to be grounded except for the four corner 10x10 square holes. The 
10x10 square holes in the corners are highly recommended to be grounded. Additionally, it is 
recommended to route high-speed traces away from mounting hole areas due to large compression 
forces from the die spring. 
 
       Figure 14 Baseboard KOZ and Grounding Pad Dimensions 


  
  23 
OCP Accelerator Module Design Specification v1.0 
 
6.5.1 SMT Nut 
Two SMT nuts with the dimensions shown in Figure 17 are to be soldered to the baseboard in the 
locations with 5.7mm diameter holes. These nuts provide the mating features to the alignment pins on 
the bottom stiffener of the mezzanine module. Clearance of the 3mm pins in the 3.6mm nuts means 
that the module will come within 0.3mm of its final position.  
MPN: Ray Home 1000401319 or equivalent 
 
Figure 15 SMT Receiving Nut for Baseboard 
6.5.2 Component Keep-out Zone 
The baseboard has a component keep-out zone of 103x166mm, as shown in Figure 14 Baseboard KOZ 
and Grounding Pad Dimensions.  
6.5.3 Grounding Pads 
As with the bottom stiffener, the baseboard has two grounding pads of size 8x42mm, for the EMI fabric-
over-foam gaskets on the stiffener to provide good contact. Refer to Section 4.3.3 for gasket MPN and 
description. 
6.6 Recommended Alignment Features 
There are three stages of engagement when installing the mezzanine module to system.  
Stage 1: Notch in top of heatsink providing visual guidance and orientation reference. Reference design 
is shown with 1mm clearances (plastic top is 103mm with a 0.5mm bumper on each side of the module). 


  
  24 
OCP Accelerator Module Design Specification v1.0 
 
 
Figure 16 Top view of four adjacent mezzanine modules with heatsinks 
 
Stage 2: Alignment pins, two 3mm pins from the OAM into two 3.6mm SMT nuts on baseboard. 
 
Figure 17 Side view (exploded) showing alignment pins being received by 1mm tall SMT nuts 
 
Stage 3: Connector housing built-in engagement (Molex Mirror Mezz gatherability: 0.76mm). 
 
Figure 18 Side view (exploded) showing mezzanine connectors doing final alignment 
 
  


  
  25 
OCP Accelerator Module Design Specification v1.0 
 
6.7 Reference Heatsink Design 
It is recommended to use an air-cooled solution for TDP equal or less than 450W modules. For modules 
which are over 450W, it is recommended to consider other solutions such as liquid cooling. 
The below figure shows the reference model of heatsink with accelerator module assembly. 
 
 
 
 
 
 
 
 
 
 
 
 
Figure 19 Reference Model of Heatsink with Accelerator Module Assembly 
 
6.7.1 Top Handle 
Due to the size and bulk of the heatsink and module assembly, a handle is recommended. The reference 
design uses a folding handle. This handle is screwed into a sheet metal panel which is then attached to 
the heat sink base with six M2.5 flathead screws. This method of attachment allows the load to be 
transferred through the more rugged base instead of through the delicate heat sink fins. 
MPN: Fivetech 62-57P-064-7-02-5 or equivalent 
Reference heatsink 
Top handle 
 Mounting screws 
Baseboard PCB 
Notch 



  
  26 
OCP Accelerator Module Design Specification v1.0 
 
 
Figure 20 Dimensioned Smart Folding Handle from Reference Design 
6.7.2 Long Screw Attachment 
A set of four M3.5, spring-loaded, Phillips head long screws are used to attach the module to the 
baseboard. Note that the reference screw provided is simply a reference and that L3 and L4 will need to 
be adjusted based on thicknesses of the baseboard and bolster plates. However, these mounting screw 
locations are fixed per the requirements of the mezzanine board layout and the baseboard layout. Each 
screw clears the top stiffener, mezzanine PCB, and bottom stiffener (including the die spring), and the 
baseboard to screw directly into the bolster plate below the baseboard PCB. It is recommended that the 
OAM is attached to the baseboard by torqueing the screws in a diagonal pattern. 
MPN of Long Screw: Wujiang Screw MDCM0359733N or similar 
MPN of Spring for Long Screw: Surpassing Hardware Spring FDJG7004010 or similar 
Figure 21 Drawing of Wujiang Screw MDCM0359733N 
 
 


  
  27 
OCP Accelerator Module Design Specification v1.0 
 
7 Thermal Specification 
7.1 Environmental Conditions 
To meet the thermal reliability requirement, the thermal and cooling solution should dissipate heat from 
the components when the module is operating at its thermal design power. The module should be able 
to operate in the following environmental conditions without any throttling or thermal issues: 
 Ambient temperature: 5°C to 35 °C 
 Approach temperature: 10°C to 48 °C, considering shadowing other components 
 Altitude: sea level to 3000 ft*, without temperature deration  
 Relative Humidity: 20% to 90% 
 Cold boot temperature: module should be able to boot and operate at an initial temperature of 
10°C 
*An extended altitude range of up to 6000ft is recommended.  
In addition, the module should be able to remain unaffected at non-operational storage temperature 
range of -20°C to 85°C. 
 
Figure 22 Module Operation Ambient Temperature 
 


  
  28 
OCP Accelerator Module Design Specification v1.0 
 
7.2 Temperature Report  
7.2.1 Temperature Sensors 
The module reports readings of ASIC temperature sensor and HBM temperature sensor to support 
software or hardware throttling, shutdown, and drive fan speed through BMC. The sensors should be 
located or calibrated to: 
 Always report the hottest junction temperature in the component  
 Keep accuracy within 3°C 
Lower temperature limit, non-critical temperature limit, and critical temperature limit should be defined 
for those temperature sensors to support throttling or shutdown features.  
7.2.2 Remaining Components 
For the remaining components that are not monitored by temperature sensors or not included in fan 
speed control (FSC), their cooling solutions should be properly designed such that: 
 Before ASIC or Memory temperature readings reach throttling thresholds, they will be 
maintained below the temperature limits. 
 When any ASIC or Memory temperature reading reaches a throttling threshold but not the 
hardware shutdown limit, these components will remain functional to support reduced 
functionality of the module. 
7.3 Thermal module info 
To enable the module with appropriate cooling solutions, supplier will provide the following thermal 
info for each product model: 
 ASIC & Memory (HBM or DRAM) junction temperature limit 
 ASIC & Memory (HBM or DRAM) junction to surface/case temperature correlations 
 Connector surface temperature limit 
 ASIC & Memory (HBM or DRAM) junction temperature range at nominal operation conditions 
7.4 Heatsink Assembly 
To minimize complexity of assembly, servicing and risk of failure, the module will meet these 
requirements: 
 Only one replaceable heatsink assembly (primary heatsink) is needed for the module, which can 
be swapped in field. 
 The other heatsink parts (i.e. secondary heatsinks) and thermal interface materials will come 
with the module, and do not need replacement over the module lifetime. 
Reliability test reports will be provided to validate lifetime of the thermal interface materials. Shock 
and Vibration test reports will be provided to validate robustness of the module assembly.  
 



  
  29 
OCP Accelerator Module Design Specification v1.0 
 
7.5 Thermal Recommendation 
7.5.1 Airflow Budget 
Considering the limit on air delivery/removal capabilities of typical infrastructures, it is recommended 
that the OAM module be capable of operating with full performance at or below an airflow/power ratio 
of 0.145 CFM/W, with ambient temperature up to 30°C at sea level. This is equivalent to an inlet/outlet 
air temperature increase of 22°F.  
 For operation at altitude, the same air temperature difference of 22°F is recommended. 
 For a single OAM that is shadowed by other components, the airflow/power ratio is calculated 
with airflow through its heatsink, and the module power 
 For an OAM shadowing other components or multiple OAMs in serial, this calculation uses the 
airflow through the flow channel, and the sum of the power of OAM modules and upstream 
components. 
 For OAM modules with power lower than 300W, an airflow/power ratio of 0.1 CFM/W or lower 
is usually achievable and recommended.  
 
Figure 23 CFM per Watt 
7.5.2 Reference Heatsink Design 
Please refer to Figure 19 Reference Model of Heatsink with Accelerator Module Assembly. To help the 
enablement of each product, a reference heatsink design will be provided, including 
 Thermal simulation model 
 3D mechanical drawing 
Performance of the reference heatsink is provided in Figure 23, the thermal resistance of which is 
calculated based on: 
𝑅௖௔=்೎ೌೞ೐ି்ಽಲ
௉೏೔೐
, 


  
  30 
OCP Accelerator Module Design Specification v1.0 
 
Where Tcase is the surface center temp of heater, TLA is the approaching temperature and Pdie is the 
power of the heater indicating the die instead of the total module power.  
Die size and power density plays an important role in the thermal performance of OAM module. As a 
general guidance, this chart provides curves of three different die (heater) sizes. Each product can make 
preliminary estimation by referring to the curve with closest size.  
 
Figure 24 Thermal resistance and pressure drop of reference heatsink 
If applicable, significant improvement can be achieved by implementing vapor chamber to assist heat 
spreading in the base. The performance of Reference heatsink design V2 with vapor chamber base is 
provided as follows: 


  
  31 
OCP Accelerator Module Design Specification v1.0 
 
 
Figure 25 Thermal resistance of reference heatsink V2 with vapor chamber 
7.5.3 Cooling Limit 
Depending on model and application, the OAM may operate at a variety of power levels. However, 
traditional air-cooled heatsinks may hit their performance limit due to the constraint on heat spreading 
technologies. Beyond a certain chassis height, fin size, and airflow rate, the improvement on thermal 
resistance of air-cooled heatsink becomes minimal.  
Package size also have significant impact on the cooling capability of OAM modules. Figure 26 provides 
the airflow needs of single OAM module at given approaching temperature, case temperature target, 
thermal interface material and die powers. Beyond 120CFM more airflow towards OAM brings 
diminishing return, which limits the max OAM power supported. This can be also used to estimate 
cooling capability of system design and fan trays.  


  
  32 
OCP Accelerator Module Design Specification v1.0 
 
  
Figure 26 Increasing need of airflow for OAM cooling as die power increases 
For a reference OAM in a typical platform with 8x OAMs, shadowing layout, it is observed that the 
maximum module power that air cooling can support is approximately 450W. Beyond this power limit, 
advanced cooling solutions are recommended to support its operation at the hotter part of the 
operational boundary condition range. These advanced cooling solutions would also be recommended 
for extended environment boundary conditions. Note that this limit may vary for different products, 
depending on die size, power distribution, and junction temperature limits.  
Open loop liquid cooling is one of the feasible cooling solutions to support modules of higher power. To 
support typical open loop liquid cooling modules designed for a 1RU (height = 44.45mm) system, it is 
recommended that OAM vendors limit the maximum distance from the lower surface of bottom 
stiffener to the top surface of the die (ASIC/HBM) to within 13mm.  
 


  
  33 
OCP Accelerator Module Design Specification v1.0 
 
 
Figure 27 Maximum height of OAM to enable liquid cooling within a 1RU system 
 
Figure 28 An Example of Open Loop Liquid Cooling setup concept for OAM 
A typical open loop liquid cooling setup (cold plate) for the OAM may include the following parts: 
 Cold plate base + thermal interface materials 
 Internal Mini/Micro channels 
 Internal Manifold 
 Coolant inlet/outlet tubes  
With a proper coolant supply, open loop liquid cooling has the potential of delivering surface-to-coolant 
thermal resistance lower than 0.05°C/W. However, it would require liquid supply and control systems to 
be established as part of the data center infrastructure.  
7.5.4 Heatsink Installation 
A lot of OAM modules use a bare die design, which may be fragile and susceptible to imbalance of 
pressure on its surface. The system integrator should contact the accelerator module supplier for the 
maximum static and dynamic pressure for the die, to guide installation of the primary heatsink to the 


  
  34 
OCP Accelerator Module Design Specification v1.0 
 
module. The static mounting pressure should also be high enough to enable optimum performance of 
the TIM material.  
We suggested that following guidelines to be followed during installation: 
 Screw head type: Philips #2 
 Tightening pattern: Diagonal 
 Tightening stage: multiple stages, 2 or 3 
 Tightening torques: (TBD) 
The mounting pressure of heatsink is determined by: 
 Max pressure the package can sustain 
 Min pressure the TIM need to deliver enough performance 
We recommend the mounting pressure range to be 30 ~ 60 psi for OAM with bare die packages. For 
engineering samples without enough assembly yield rate learnings, we recommend starting with an 
initial mounting pressure of 15~30 psi. For lid-covered OAM packages, the mounting pressure is yet to 
be explored.  
7.5.5 Thermal Interface Material 
The thermal interface material between the die (ASIC/HBM) and the primary heatsink should maintain a 
thermal conductivity of at least 4W/mK through the end of its life. This is equivalent to approximately 
6°C temperature difference between the heatsink base and the die top surface, for a bond line thickness 
of 0.1mm and heat flux of 24.4W/cm2, which is also equivalent to 300W uniformly distributed over a 
surface area of 44mm x 28mm.  
Maximum warpage of the package should not exceed 0.2mm. This could potentially lead to an average 
bond line thickness of 0.1mm for the TIM. Varying for different die sizes, TIM could easily contribute 
0.01 ⁰C/W ~ 0.08 ⁰C/W, up to 50% of total thermal resistance: 



  
  35 
OCP Accelerator Module Design Specification v1.0 
 
 
Figure 29 Thermal resistance across TIM layer at different bond line thicknesses 


  
  36 
OCP Accelerator Module Design Specification v1.0 
 
8 Accelerator Module Electrical Specification 
8.1 Electrical Connector 
The module utilizes two 688pin Molex Mirror Mezz connectors. It is a BGA attached connector and 
supports bit rates up to 56Gbps NRZ or 112 Gbps PAM4 in a 90 Ohms nominal impedance ± 5% 
tolerance which make it compatible to support typical 85 Ohms based interfaces such as PCIe Gen3/4/5 
as well as other 100 Ohms based high speed interfaces. All power and I/O signals are routed through the 
two connectors down to the system baseboard. The system baseboard should connect these signals to 
the appropriate circuitry depending on the required feature sets. The below table lists the electrical 
requirements for the module connectors.  
Table 3 Electrical Requirements for Molex Mirror Mezz 
Items Mirror Mezz  
Data Rate Support 25/28/32/56Gbps NRZ , 56G/112G* PAM4 
Connector Impedance 90ohm ± 5% 
Differential pairs per two connectors 172 pairs 
Pin Pitch 0.9mm and 1.3mm 
Current Rating per pin @80C ambient temp, 
1.5oz copper 
1A/pin after 20% derating 
Max Voltage Application 30V AC (OAM supports 60V after Molex’s pin 
assignment review) 
Connector insertion cycles 100cycles 
Withstand voltage 500V min 
Low Level Contact Resistance (max initial): 30mΩ for 5mm stack height 
Insulation resistance 1-MΩ min 
Intra-pair skew <=5 ps 
*note:  
 
Figure 30 Mirror Mezz Connector Footprint 
 


  
  37 
OCP Accelerator Module Design Specification v1.0 
 
 
Figure 31 Mirror Mezz Connector Pin to Pin Pitch 
8.2 Mezzanine Module Connector Pinout Quadrants 
   
 
Figure 32 Mezzanine Connectors Pinout Quadrants 
The OAM Connector 0 has the following interfaces: 
 54V/48V and 12V input power 
 x16 SerDes to connect to host 
 3 x16 SerDes for accelerator to accelerator communication 
o X16 may be split to sub links like 2* x8s or 4* x4s or 16*x1s. 
o If the ASIC or ASICs on the module only support x8 or x4 per SerDes, it should start from 
Lane0 from the SerDes, e.g. lane [7:0] or lane [3:0]. 
o We do not recommend lane reversal support on the baseboard due to modules having 
the option to be 1X16 link or 2X8 or 4X4 links. 
x16 
SERDES C 
x16 
SERDES B 
x16 
SERDES 6 
Host, 
Power 
x16 
SERDES 3 
x16 
SERDES 2 
X16 
SERDES 1 
X16   
SERDES 7 
x16 
SERDES 4 
x16 
SERDES 5 



  
  38 
OCP Accelerator Module Design Specification v1.0 
 
 Other single ended signals like PRESNT#, SMBus, GPIOs etc. 
The OAM Connector 1 has the following interfaces: 
 Power pins for 3.3V 
 Other single ended signals like JTAG, GPIOs etc.  
 Up to 4 SerDes for accelerator to accelerator communication or other purposes: 
o SerDes 4, 5, 6 and 7 are up to x16 lanes which can be split to X8s, X4s or X1s.  
 SerDes 7 may be defined for different use cases: 
o This link could be the 7th SerDes for some cases to have fully connected interconnect 
between the modules 
o It could be the 2nd link to host for the ASIC(s) on the module, e.g. a full x16 link, 2 x8, or 4 
x4 links. 
o Or it could be special defined link by some ASICs. E.g., it could be a downstream port for 
the ASIC on the module. 
 
8.3 Accelerator Module Pinout Description 
The detail pin mapping to connectors will be provided in separated spreadsheet. This section only shows 
the pin list and description. 
Table 4 Accelerator Module Pinouts 
Signal Module 
Direction 
POV 
Description Voltage Required 
or Optional 
Total 
Diff 
Pins 
Total 
Single 
Pins 
Conn 0 or 1 
P48V Power 
Input 
44V-59.5V main 
voltage for high power 
applications. Up to 
700W when Vin=>44V. 
The module should be 
able to operate at 40V 
to 44V but at lower 
power (motherboard 
to drive PWRBRK# for 
Vin <44V). 
44V-
59.5V Required   16 Conn0 
P12V1 Power 
Input 
12V mandatory Board 
Infrastructure Power. 
Up to 50W 
12V Required   5 Conn0  
P12V2 Power 
Input 
12V main Power for 
low power 
applications. Up to 
300W. For 12V 
motherboard/module 
designs, P12V1 and 
P12V2 can be shorted 
12V 
Required 
for P12V 
based 
OAM 
  27 Conn0 



  
  39 
OCP Accelerator Module Design Specification v1.0 
 
together for up to 
350W combined power 
P3V3 Power 
Input 
3.3V Main Power. Up 
to 5W 3.3V Required   2 Conn0  
PVREF Power 
Output 
Low voltage output for 
GPU/ASIC sideband I/O 
reference on 
motherboard 
components.  Module 
should provision 
maximum 0.5A to be 
provided to the 
motherboard. Vref can 
be any value between 
1.5V to 3.3V set as per 
GPU/ASIC sideband I/O 
voltage. 
Vref Required   2 Conn0 
PETp/n 
[15:0] Output 
PCIe or equivalent host 
link Transmit 
differential pairs. 
Module Transmit, Host 
Receive. Note: AC 
coupling caps must be 
placed on the 
motherboard side.  
  Required 16   Conn0  
PERp/n 
[15:0] Input 
PCIe or equivalent host 
link Receive differential 
pairs. Module Receive, 
Host Transmit. Note: 
AC coupling caps must 
be placed on the 
motherboard side.  
  Required 16   Conn0 
SERDES_1
Tp/n 
[15:0] 
Output 
SerDes link 1 Transmit 
differential pairs. AC 
caps must be placed on 
Module/die (if 
required) 
  Required 16   Conn0  
SERDES_1
Rp/n 
[15:0] 
Input SerDes link 1 Receive 
differential pairs.   Required 16   Conn0 
SERDES_2
Tp/n 
[15:0] 
Output 
SerDes link 2 Transmit 
differential pairs. AC 
caps must be placed on 
Module/die (if 
required) 
  Required 16   Conn0  



  
  40 
OCP Accelerator Module Design Specification v1.0 
 
SERDES_2
Rp/n 
[15:0] 
Input SerDes link 2 Receive 
differential pairs.   Required 16   Conn0 
SERDES_3
Tp/n[15:0
] 
Output 
SerDes link 3 Transmit 
differential pairs. AC 
caps must be placed on 
Module/die (if 
required) 
  Required 16   Conn0  
SERDES_3
Rp/n 
[15:0] 
Input SerDes link 3 Receive 
differential pairs.    Required 16   Conn0 
SERDES_4
Tp/n[15:0
] 
Output 
SerDes link 4Transmit 
differential pairs. AC 
caps must be placed on 
Module/die (if 
required) 
  Required 16   Conn1  
SERDES_4
Rp/n 
[15:0] 
Input SerDes link 4 Receive 
differential pairs.   Required 16   Conn1 
SERDES_5
Tp/n 
[15:0] 
Output 
SerDes link 5 Transmit 
differential pairs. AC 
caps must be placed on 
Module/die (if 
required) 
  Required 16   Conn1  
SERDES_5
Rp/n 
[15:0] 
Input SerDes link 5 Receive 
differential pairs.   Required 16   Conn1 
SERDES_6
Tp/n 
[15:0] 
Output 
SerDes link 6 Transmit 
differential pairs. AC 
caps must be placed on 
Module/die (if 
required) 
  Required 16   Conn1  
SERDES_6
Rp/n 
[15:0] 
Input SerDes link 6 Receive 
differential pairs.   Required 16   Conn1 
SERDES_7
Tp/n 
[15:0] 
Output 
SerDes Reserved Link 
Transmit differential 
pairs. Interconnect 
requirements defined 
by Module and System 
integrator. AC caps 
must be placed on the 
Motherboard (if 
Required) 
  Optional 16   Conn1  
SERDES_7
Rp/n 
[15:0] 
Input 
SerDes Reserved Link 
Receive differential 
pairs. Interconnect 
  Optional 16   Conn1 



  
  41 
OCP Accelerator Module Design Specification v1.0 
 
requirements defined 
by Module and System 
integrator. AC caps 
must be placed on the 
Motherboard (if 
Required) 
PE_REFCL
Kp/n Input 
PCIe Reference Clock. 
100MHz PCIe Gen 5 
compliant.  
  Required 1   Conn0  
AUX_100
M_REFCL
Kp/n 
Input 
 100MHz PCIe Gen 5 
compliant Auxiliary 
Reference Clock. 
  Required 1   Conn1 
DWN_REF
CLKp/n Output Downstream Reference 
Clock. Vendor specific.   Optional 1   Conn1  
AUX_156
M_REFCL
Kp/n 
Input 
156.25MHz Auxiliary 
Reference Clock, +/-
50ppm. System 
integrator may collect 
jitter requirement from 
OAM suppliers.  
 Required 1  Conn1 
PERST# Input CEM Compliant PCIe 
Reset 3.3V Required   1 Conn0  
WARMRS
T# Input Warm Reset Vref Optional   1 Conn0 
DWN_PER
ST# Output Down device PCIe 
Reset. Vendor specific. 3.3V Optional   1 Conn1  
HOST_PW
RGD Input 
Host power good. 
Active high when P48V, 
P12V1/P12V2, P3V3 
voltages are stable and 
within specifications. 
This is considered the 
“Power Enable” signal 
for the module. 
3.3V Required   1 Conn0 
MODULE_
PWRGD Output 
Module power good. 
Active high when the 
module has completed 
its own power up 
sequence and is ready 
for PERST# de-
assertion 
3.3V Required   1 Conn0  
PWRBRK# Input 
Emergency power 
reduction. CEM 
Compliant Power Break 
3.3V Required   1 Conn0 
PWRRDT#
[1:0] Input Power Reduction GPIO 
to instruct Oam to go 3.3V Required  2 Conn1 



  
  42 
OCP Accelerator Module Design Specification v1.0 
 
certain stage to reduce 
power 
11 - default state L0, 
normal power 
10 - L1, 1st level power 
reduction.  
01 - L2, 2nd level 
power reduction.  
00 - L3, max power 
reduction.  
Details defined by 
specific OAM product 
specification. 
THERMTR
IP# Output 
Catastrophic thermal 
event for module 
components. Active 
low and latched by the 
Module logic. Released 
when the motherboard 
power cycles the 
module input voltages 
3.3V Required   1 Conn1 
MODULE_
ID[4:0] Input 
Module node identifier 
(e.g. Module #0, 
#1,…#n). Module has 
weak PU to drive to 1 
by default. 
GND Required   5 Conn0  
LINK_CON
FIG[4:0] Input 
Mezz Module Host 
Interface/SerDes Link 
Configuration and 
topology. See link 
config table for details. 
Module has weak PU to 
Vref to drive high by 
default. 
GND Required   5 Conn1 
PE_BIF[1:
0] Output 
x16 Host Interface 
Bifurcation 
Configuration. This 
output of the module 
informs the host if it 
needs to bifurcate the 
PCIe interface to the 
module.   
00 = one x16 PCIe host 
interface 
01 = bifurcation into 
two x8 PCIe host 
interfaces 
Vref Required   2 Conn1  



  
  43 
OCP Accelerator Module Design Specification v1.0 
 
10 = bifurcation into 
four x4 PCIe host 
interfaces 
11 = reserved" 
Tied to GND on module 
for logic 0, leave open 
on module for logic 1; 
pull up on baseboard 
PLINK_CA
P Output 
"P" Port Module 
Capability support: 
 '0' = PCIe only support 
'1' = Alternate protocol 
supported 
The host system 
requests an alternate 
host link protocol by 
pulling up 
LINK_CONFIG[0] and 
the Module informs 
the system of protocol 
support on the "P" link 
via this pin. If the 
module only supports 
PCIe as host, this signal 
is PD on the module. 
Vref Required   1 Conn1 
SMBus_SL
V_D 
Bi-
directio
nal 
Slave SMBus data  3.3V Required   1 Conn0  
SMBus 
_SLV_CLK Input Slave SMBus clock 3.3V Required   1 Conn0 
SLV_ALER
T# Output Slave alert indication 3.3V Required   1 Conn0  
I2C_D 
Bi-
directio
nal 
Master I2C/SMBus 
data. PU on OAM.  Vref Required   1 Conn0 
I2C _CLK Output Master I2C/SMBus 
clock. PU on OAM. Vref Required   1 Conn0  
UART_TX
D Output Serial Port Transmit 3.3V Required   1 Conn0 
UART_RX
D Input Serial Port Receive 3.3V Required   1 Conn0  
JTAG0_TR
ST Input Low Voltage ASIC/GPU 
JTAG Test Reset Vref Required   1 Conn0 
JTAG0_T
MS Input Low Voltage ASIC/GPU 
JTAG Test Mode Select Vref Required   1 Conn0  
JTAG0_TC
K Input Low Voltage ASIC/GPU 
JTAG Test Clock Vref Required   1 Conn0 



  
  44 
OCP Accelerator Module Design Specification v1.0 
 
JTAG0_TD
O Output Low Voltage ASIC/GPU 
JTAG Test Output Vref Required   1 Conn0  
JTAG0 
_TDI Input Low Voltage ASIC/GPU 
JTAG Test Input Vref Required   1 Conn0 
JTAG1 
_TRST Input High Voltage JTAG Test 
Reset 3.3V Optional   1 Conn1  
JTAG1 
_TMS Input High Voltage JTAG Test 
Mode Select 3.3V Optional   1 Conn1 
JTAG1 
_TCK Input High Voltage JTAG Test 
Clock 3.3V Optional   1 Conn1  
JTAG1 
_TDO Output High Voltage JTAG Test 
Output 3.3V Optional   1 Conn1 
JTAG1 
_TDI Input High Voltage JTAG Test 
Input 3.3V Optional   1 Conn1  
CONN1_I
NITMODE Output 
QSFP-DD Connector 1 
Module Initialization 
mode 
Vref Optional   1 Conn1 
CONN1_I
NT# Input QSFP-DD Connector 1 
Module Interrupt Vref Optional   1 Conn1  
CONN1_
MODPRS# Input QSFP-DD Connector 1 
Module Present Vref Optional   1 Conn1 
CONN1_
MODSEL# Output QSFP-DD Connector 1 
Module Select Vref Optional   1 Conn1  
CONN1_R
ESET# Output QSFP-DD Connector 1 
Module Reset Vref Optional   1 Conn1 
CONN1_G
REEN_LED Output QSFP-DD Connector 1 
GREEN STATUS LED Vref Optional   1 Conn1  
CONN1_Y
ELLOW_L
ED 
Output QSFP-DD Connector 1 
YELLOW STATUS LED Vref Optional   1 Conn1 
CONN2_I
NITMODE Output 
QSFP-DD Connector 2 
Module Initialization 
mode 
Vref Optional   1 Conn1  
CONN2_I
NT# Input QSFP-DD Connector 2 
Module Interrupt Vref Optional   1 Conn1 
CONN2_
MODPRS# Input QSFP-DD Connector 2 
Module Present Vref Optional   1 Conn1  
CONN2_
MODSEL# Output QSFP-DD Connector 2 
Module Select Vref Optional   1 Conn1 
CONN2_R
ESET# Output QSFP-DD Connector 2 
Module Reset Vref Optional   1 Conn1  
CONN2_G
REEN_LED Output QSFP-DD Connector 2 
GREEN STATUS LED Vref Optional   1 Conn1 
CONN2_Y
ELLOW_L
ED 
Output QSFP-DD Connector 2 
YELLOW STATUS LED Vref Optional   1 Conn1  



  
  45 
OCP Accelerator Module Design Specification v1.0 
 
PRSNT0# Output 
Module present pin 
connector 0. Tied to 
GND through 1K 
resistor on module 
side. 
GND Required   1 Conn0 
PRSNT1# Output 
Module present pin 
connector 1. Tied to 
GND through 1K 
resistor on module side 
GND Required   1 Conn1  
SCALE_DE
BUG_EN Output 
At-a-scale debug 
enable on the module. 
Isolates any 
motherboard JTAG 
debug path when logic 
high 
3.3V Required   1 Conn1 
DEBUG_P
ORT_PRS
NT# 
Input 
Presence signal for 
debug port in 
motherboard. Notifies 
logic in the module the 
debug access is being 
used by the 
motherboard debug 
connector. Debug port 
on baseboard present 
when logic low 
GND Required   1 Conn1  
MNGMT_
LINK0Tp/
n 
Output 
Vendor specific module 
to module 
management link port 
0 transmit. Required 
for some accelerators. 
Check with accelerator 
vendor. 
  Required 1   Conn1 
MNGMT_
LINK0Rp/
n 
Input 
Vendor specific module 
to module 
management link port 
0 receive. Required for 
some accelerators. 
Check with accelerator 
vendor. 
  Required 1   Conn1  
MNGMT_
LINK1Tp/
n 
Output 
Vendor specific module 
to module 
management link port 
1 transmit. Required 
for some accelerators. 
Check with accelerator 
vendor. 
  Required 1   Conn1 



  
  46 
OCP Accelerator Module Design Specification v1.0 
 
MNGMT_
LINK1Rp/
n 
Input 
Vendor specific module 
to module 
management link port 
1 receive. Required for 
some accelerators. 
Check with accelerator 
vendor. 
  Required 1   Conn1  
TEST0 Input   Vref Optional   1 Conn0 
TEST[4:1] Input   Vref Optional   4 Conn0 
TEST5 I/O   Vref Optional   1 Conn0 
TEST6 I/O   Vref Optional   1 Conn0 
TEST7 Output   Vref Optional   1 Conn0 
TEST8 Input   Vref Optional   1 Conn0 
TEST9 Input   Vref Optional   1 Conn0 
TEST10 Input   Vref Optional   1 Conn1 
TEST11 Output   Vref Optional   1 Conn1 
TEST12 Input   Vref Optional   1 Conn1 
TEST13 Input   Vref Optional   1 Conn1 
TEST14 Input   Vref Optional   1 Conn1 
MANF_M
ODE# Input 
Manufacturing Mode 
1: Normal operation 
0: Module enter into 
manufacturing mode 
3.3V Optional   1 Conn0 
FW_RECO
VERY# Input 
On board 
manageability boot 
recovery mode 
1: Normal operation 
0: Firmware Recovery 
boot mode 
3.3V Required   1 Conn0 
TEST_MO
DE# Input 
Compliance Test Mode 
1: Normal operation 
0: ASIC/GPU enter into 
electrical compliance 
mode 
Vref Required   1 Conn0 
RFU[3:0]   Reserved for future use       4 Conn0 
RFU[24:4]   Reserved for future use       21 Conn1 
 
 
 



  
  47 
OCP Accelerator Module Design Specification v1.0 
 
 
Figure 33 – Mezzanine Connector Pin map 
 
 
Figure 34 – Mezzanine Connector Pin Out View Reference 
8.4 Accelerator Module Power Profiles 
This section defines the maximum thermal design power (TDP) the module can support as well the 
excursion design power (EDP). 
8.4.1 Thermal Design Power TDP 
The module supports up to 350W TDP if the input nominal voltage is 12V. The module supports up to 
700W if the input nominal voltage is 48V or 54V. 
The accelerator baseboard supplies power to the module through the Mirror Mezz Connector0 power 
pins. There are 3 power rails defined in this document to accommodate both 12V and 48V (or 54V) 
modules. The current capability and power status are as the table below. The power is available on state 
S0 only. Only five P12V power pins are mandatory when the supply power is 48V (16 pins), and the rest 
of the P12V pins can be NC.  When the baseboard supply power is 12V, P48V can be NC. The baseboard 
can supply all 3 power rails and supports both 12V and 48V modules. 
Table 5 Power Rails 
Power Rail Voltage Tolerance # of pins Current Capability Status 
P12V 11V min to 13.2V max 27 27A (when at 11V) Normal Power 
P12V Mandatory 11V min to 13.2V max 5 5A (when at 11V) Normal Power 
P48V 44V min to 60V max 16 16A (when at 44V) Normal power 
P3.3V 3.3V±10%(max) 2 2A Normal power 
Mezzanine ModuleCONNECTOR #2 CONNECTOR #1ASICArrow denotes viewing direction



  
  48 
OCP Accelerator Module Design Specification v1.0 
 
Note: To support even higher TDP accelerator modules, we can further bypass 12V to provide more 48V 
and vice versa. Baseboard designers should consider module detection when mixing different modules 
in the same system. 
8.4.2 Excursion Design Power EDP 
System baseboard designers should be sure to support the accelerator module’s excursion design power 
(aka EDP). The accelerator module VR electrical design must be designed to handle the instantaneous 
peak power short period (usually it is on the order of a µs) with low duty cycle. The VR’s thermal design 
should be robust enough to handle lower power EDP level (e.g. 1.1x TDP) for ms level interval without 
asserting VR HOT over temperature alert. The system integrator should work with the module suppliers 
closely to ensure that the system baseboard supplies enough power to the module without triggering 
under voltage protection.  
Table 6 Excursion Design Power Example 
EDP Duration 
2x TDP <= 20µs 
1.6x TDP <=2ms 
1.5x TDP <=5ms 
1.2x TDP <=10ms 
1.1x TDP <=20ms 
 
8.5 System power sequencing 
System designers should follow the below power sequence requirement to implement the design. It is 
recommended to check with each specific module specification to ensure the modules work properly. 
 
Figure 35 OCP Accelerator Module Power Sequence 
Notes:  
1) If the accelerator modules with the baseboard are in the disaggregated design from the host 
system, the HOST_PWRGD is the baseboard power good indication signal.  


  
  49 
OCP Accelerator Module Design Specification v1.0 
 
2) All voltages on the baseboard that OAM plugs into must be within specification before 
HOST_PWRGD is asserted; 
3) HOST PWRGD is the enable signal to the voltage regulators on the OAM; 
4) As the voltage planes on the module ramp up, the reference clocks from the baseboard will 
begin to run; 
5) After all the voltages on the module are within specification, the module asserts 
MODULE_PWRGD to the baseboard; 
6) At least 100ms after Module_PWRGD assertion, the baseboard will de-assert the PCIe reset 
signal(PERST#) to the module. 
7) The optional WARMRST# signal de-asserts at the same time or later than the PERST# signal is 
de-asserted. 
  



  
  50 
OCP Accelerator Module Design Specification v1.0 
 
8.6 Mezzanine Module Insertion Loss 
The module interconnection channel total insertion loss at 14.025Ghz should not be over -8dB. The 
system integrator may contact the module supplier for details about the interconnection channel 
insertion loss and plan system baseboard design accordingly. For other speed is over 14.025Ghz, the 
system integrator should work with module supplier closely to determine the loss budget on the module 
as well as on the baseboard. 
Total Tx or Rx loss on Module +mated Mezz 
Connectors @14.025Ghz up to 8dB  
 
 
Figure 36 Channel loss Budget (PCB-only Topology) 
Total channel loss budget = Tx module + baseboard + Rx module 
Example:  
Total channel loss budget = 30 dB (14.025 GHz) 
• Tx module = 8 dB 
• Rx module = 8 dB 
• Baseboard budget = 30 dB – 8 dB – 8 dB = 14 dB 
 


  
  51 
OCP Accelerator Module Design Specification v1.0 
 
 
Figure 37 Channel loss budget (Cabled Topology) 
Total channel loss budget = Tx module + Tx baseboard + QSFP-DD assembly + Rx baseboard + Rx 
module 
Example:  
Total channel loss budget = 30 dB (14.025 GHz) 
• Tx module = 8 dB 
• Rx module = 8 dB 
• QSFP-DD = 5 dB 
• Tx + Rx baseboard budget = 30 dB – 8 dB – 8 dB – 5.0 dB = 9 dB 
 
8.7 Management link  
Management link 0/1 are defined for OAM to communicate with each other. When host interface is 
PCIe, management links are routed in a ring as illustrated in the following diagrams with Management 
link 0 on one module connecting to management link 1 on the next module. 
 
Figure 38 Management Link Routing Guidance 


  
  52 
OCP Accelerator Module Design Specification v1.0 
 
9 Mezzanine Module Interconnect Topologies 
This section describes the recommended interconnection topology for a system with 4, 8, and 16 
accelerators.  
9.1 Module ID 
The following figure shows the MODULE_ID[4:0] strapping for physical orientation of modules when 8 
interconnected Accelerators are used. 
 
Figure 39 Required MODULE_ID[4:0] assignments for motherboards with 8 interconnected modules 
Detail port to port assignment is based on system placement and routing length. Module to module 
interconnect may decrease to 4 ports if the module only supports 4. Module to module interconnect link 
may only utilize 8 lanes if the module defines 8 lanes per link. 
The following Figure shows the required MODULE_ID[4:0] assignments when only 4 modules are 
connected as two rows of two. 


  
  53 
OCP Accelerator Module Design Specification v1.0 
 
 
Figure 40 MODULE_ID[4:0] assignments when four only in two rows of two 
9.2 Interconnect Topology 
This section describes different interconnect topologies and routing guidance for 8 OAMs with different 
port numbers. If all 7 ports are configured and routed as x16, there is no additional port(s) for 
expansion. To reserve expansion port(s), we suggest limiting on board Interconnect links up to x8. 2nd 
half of port 1(x8, also referred as 1H) is reserved for expansion by default. 2nd half of port 4,6,7 are used 
in X8 based full connected topology at section 9.2.4.   
9.2.1 Hybrid Cube Mesh (HCM) for 6 ports per OAM 
Below Figure shows an example topology (Hybrid Cube Mesh) of 8 modules in a baseboard.  
 
Figure 41 Topology Example for Modules with 3/4/6 ports – Hybrid Cube Mesh 


  
  54 
OCP Accelerator Module Design Specification v1.0 
 
The interconnect topology in this Figure supports the following OAM module interconnects: 
o 3 links and two fully connected quads using links: 1, 3, and 4 
o 4 link Hybrid Cube Mesh using links: 1, 3, 4, and 6 
o 6 link Hybrid Cube Mesh using links: 1, 2, 3, 4, 5, and 6 
Here is the routing suggestion for Hybrid Cube Mesh: 
 
Figure 42 6 port Hybrid Cube Mesh Routing Recommendation 
9.2.2 Almost Fully Connected 
Depending on different workloads, if the module has 6 links, the other topology that can be considered 
is Almost Fully Connected (also called as Chordal Ring). Each module connects to the other 6 of the 
modules with 1 link. Figure below illustrates the topology:  
 
Figure 43 Almost Fully Connected Topology 


  
  55 
OCP Accelerator Module Design Specification v1.0 
 
The interconnect topology in below Figure supports the following OAM module interconnects: 
o 6 x16 links Chordal Ring (Almost Fully Connected) using links: 1, 2, 3, 4, 5, and 6 
Here is the routing suggestion:  
 
Figure 44 Routing Recommendation for Almost Fully Connected Topology 
9.2.3 Hybrid Cube Mesh for 8 ports per OAM 
The Figure below shows an example of 8 ports topology (Hybrid Cube Mesh) of 8 modules in a 
baseboard. Please follow port mapping to design OAM in order to be able to fit in the universal OAM 
baseboard.  Port 4/6 are connected through QSFP-DD cables for single 8 module system. These QSFP-DD 
cables can also be used for expansion (scale out).  
 
Figure 45 8-port Hybrid Cube Mesh Topology 


  
  56 
OCP Accelerator Module Design Specification v1.0 
 
And here is routing suggestion: total 4 layer, two layers for TX two layers for RX. Port 4/6 are connected 
through cables. 
 
Figure 46 8-port HCM topology routing guide 
 
9.2.4 Fully Connected 
If the module has 7 or more links, each module can communicate with any of the other 7 modules 
directly. The topology is fully connected. Each link can be up to X16 in FC topology (no extra link or port 
for scale out if it’s X16 per link here).  
 
Figure 47 Fully Connected Topology 
Here is the routing suggestion for 7X16 links fully connected topology:  


  
  57 
OCP Accelerator Module Design Specification v1.0 
 
 
Figure 48 Routing Recommendation for Fully Connected Topology 
 
9.2.5 Combined FC/HCM Topology 
For fully connect with expansion consideration, the baseboard link is suggested to route as X8( 1st X8 of 
each port, 1L-7L), leaving 2nd X8 of each SerDes port for expansion or embedding other topology. Here is 
7X8 fully connected topology combined with 6X8 hybrid cube mesh topology (X8 FC + X8 6 port HCM):  
 
Figure 49 Combined FC/HCM Topology 
Link 1,4,6,7 has total 16 lanes and link 2,3,5 has total 8 lanes in Figure 49:  
o Fully connected: 7 x8 links using port 1-7 first X8(1L-7L); 
o 2nd half of port 1(1H) can be used for expansion (scale out); 
o 6 port HCM: all 6 ports are in connector 1 only. X16 link for port 4/6, X8 link(5L) for port 5 
and 2nd half of port 7(7H)  
 


  
  58 
OCP Accelerator Module Design Specification v1.0 
 
Below figure shows the detail port mapping and routing guide:  
 
Figure 50 Detail port mapping and routing guidance 
Port 4/6(both 4L/6L and 4H/6H), port 5L, 7H are used for 6X8 HCM. This is how it’s embedded to this 
combined topology:  
 
Figure 51 Embedded HCM Topology 
 
9.2.6 4D Hypercube 


  
  59 
OCP Accelerator Module Design Specification v1.0 
 
16 modules with 6 links per module the interconnect topology could be a 4d hypercube:  
 Four fully connected quads 
 Each quad connected to the other 3 quads at all four corners 
 The green links below matches the green line in the 4d hypercube 
As one single PCB cannot fit all 16 modules, this topology interconnect will have cable or backplane to 
connect between PCBs. Depending on whether one single PCB holds 4 modules or 8 modules, the 
interconnect path may be different. The system integrator may discuss with the module supplier for 
details. The module defines two QSFPDD ports as the potential scale up solution.  
 
Figure 52 4D Hypercube 
9.3 LINK_CONFIG[4:0] 
The 5 link configuration strapping bits are pulled up on modules that use them.   These bits are strapped 
to ground on the baseboard to select logic 0, or left floating on the baseboard to select logic 1.   Some 
accelerators use these LINK_CONFIG[4:0] strapping bits to determine the interconnect topology for the 
links between modules and to determine the protocol of the “P” Link. 
Encodings not listed in the table below are currently un-defined. 
Table 7  LINK_CONFIG[4:0] Encoding Definitions 
LINK_CONFIG[4:0] Definition 
00000 Reserved for Accelerator Test use by Accelerator 
Vendor. 
xxxx0 (except for 00000) Indicates the “P” link is PCIe 
01000 6 link HMC, 4 link HMC, and two 3 link fully 
connected quads as connected in Figure 41. 
00100 6 x16 almost fully connected 
00110 7 x16 fully connected 
01010 4 or 6 x8 link HMC, 7x8 links fully connected, and 
two 3 x8 link fully connected quads as connected 
in Figure 50. 


  
  60 
OCP Accelerator Module Design Specification v1.0 
 
01100 8 link HMC as in Figure 45.  
xxxx1 (except for 11111) Indicates the “P” link is an alternate protocol 
other than PCIe. 
11111 Indicates an alternate means for identifying the 
link interconnect topology and configuration is 
used. 
 
9.4 Accelerator Interconnect PCB Topology  
It is recommended to keep the stub for interconnect link less than 10mils. System integrator should 
work with module suppliers to plan the PCB routing and address the signal integrity concern carefully.  
 
Figure 53 – Accelerator Interconnect PCB Topology 


  
  61 
OCP Accelerator Module Design Specification v1.0 
 
10 Mezzanine module reference system design 
This section gives a system design concept as a reference. Figure 54 Reference System Design shows 8 
OAM modules. The plastic top provides a 0.5mm bumper on each side of the 102mm width OAM, and 
the 1mm gap between each module assembly provides rough alignment, guidance, and keying as 
described in Section 6.6. An air baffle is designed into the 33.8mm space to prevent air bypass in the 
system. Note that the front and rear rows are oriented 180 degrees opposite as indicated in Section 
9.Recommended Alignment Features 
 
Figure 54 Reference System Design 
 
 


  
  62 
OCP Accelerator Module Design Specification v1.0 
 
11 System Level Communication 
This section describes a common set of management requirements for this OAM. 
11.1 Sideband Management Interface  
The OCP Accelerator Mezz module sideband management interface is used by a Management 
Controller (MC) or Baseboard Management Controller (BMC) to communicate with the Accelerator 
module. Table 8 below summarizes the sideband management interfaces.  
Table 8 Sideband Management Interface 
Requirement  Voltage Level Required 
SMBus 2.0 compliant physical interface(Slave) 3.3V Yes 
JTAG physical interface(primary) LV I/O  Yes 
I2C/SMBus 2.0 compliant physical interface(Master) LV I/O Optional* 
JTAG physical interface(secondary) 3.3V Optional 
*Note: The master I2C/SMBus physical interface is required for scale out, baseboard FRU access 
through in-band.  
The OAM communicates with the Baseboard Management Controller (BMC) via SMBus by using: 
 Standard Intelligence Platform Management Bus (IPMB) and Intelligent Platform 
Management Interface (IPMI) commands. 
 SMBus command 
11.2  Sensor Reporting 
An OAM module may have several silicon components including one or more ASICs implementing 
acceleration functions. For the system management, it is important that related sensors (voltage, 
current/power, temperature…etc) of these components can be retrieved over sideband interfaces. 
The sensor reporting interface will only be accessible in main power mode (S0). Table 9 summarizes the 
sensors reporting list. The report from these sensors improves the system monitoring/management and 
allows the baseboard management device to access key components on the module. It is recommended 
that the voltage/current/power sensor reporting accuracy is within ± 2% and the temperature reporting 
accuracy is within ±3°C. 
Table 9 Sensor List 
Sensor List Remark 
Power/Current (Mem, core, module level)  
Voltage (core,mem)  
ASIC Temp (hot spot and edge temp)  
ASIC Tjmax  
Mem Temp for each stack  
Core Power VR Temp  
Core Power VR Vol  



  
  63 
OCP Accelerator Module Design Specification v1.0 
 
Inlet sensor Need define common 
location 
Outlet sensor  
 
11.3 Error Monitoring/Reporting 
System Management Controller (MC) or Baseboard Management Controller (BMC) shall be able to 
monitor and access the accelerator module‘s internal registers as needed to set thresholds, clear status, 
determine error counts and syndromes (SW driven interrupt or an Alert pin), and identify error 
sources/Syndromes etc. 
 Mem 
 PCIe  
 ASIC 
 Interconnect Links 
 Others, I/O 
11.4 Firmware Update 
The accelerator module should support secure boot. The ASIC(s) needs to check signature of the 
firmware each time it boots against keys programmed in OTP. 
 It will check using public keys burned into the silicon. 
 If the signature does not match, the chip will not boot. 
 Enter some sort of recovery mode allowing firmware to be flashed by the host. 
 Time-of-check-time-of-use (TOCTOU) attacks must be prevented. Specifically, host should NOT 
be able to modify firmware image once signature checks begin, and should also be unable to 
modify the stored or running firmware image after signature checks have been completed. 
  Key-revocation and anti-rollback protection must be provided for the accelerator firmware. 
 Protection against PDoS attacks must be provided. 
Module supplier should provide the relevant tool for out-of-band firmware updates. 
11.5 Power Capping  
Module supplier should provide either the tool or SMBus/IPMI commands to do power capping for the 
module.  
11.6 FRU Information  
System Management Controller (MC) or Baseboard Management Controller (BMC) shall be able to 
access related internal registers to get module information, such as vendor ID, device ID, Manufacturing 
Serial number, firmware version, Bifurcation information, etc. 
11.7 IO Calibration 



  
  64 
OCP Accelerator Module Design Specification v1.0 
 
System Management Controller (MC) or Baseboard Management Controller (BMC) shall be able to get 
DDR/PCIe/interconnect training status and margin information. Special tools and API may need to be 
provided by module vendors.  
 



  
  65 
OCP Accelerator Module Design Specification v1.0 
 
12 Environmental 
12.1 Environmental Requirements 
The OAM shall meet the following environmental requirements: 
 Gaseous Contamination: Severity Level G1 per ANSI/ISA 71.04-1985 
 Ambient operating temperature range: 5°C to +35°C 
 Operating and Storage relative humidity: 20% to 90% (non-condensing) 
 Storage temperature range: -20°C to +70°C 
 Transportation temperature range: -55°C to +85°C (short-term storage) 
 Operating altitude with no de-ratings: 3048m (10000 feet) – recommended as this is a Facebook 
spec and standard for Telco operation 
12.2 Regulation 
The vendor needs to provide CB reports of the mezzanine module. These documents are needed to have 
rack level CE. The OAM should be compliant with RoHS and WEEE.  The PCB should have a UL 94V-0 
certificate.  



  
  66 
OCP Accelerator Module Design Specification v1.0 
 
13 Revision History 
Author  Description Revision Date 
Whitney Zhao  Initial Release 0.1 6/29/2018 
Whitney Zhao  Add pin list 0.2 11/09/2018 
Tiffany Jin 
Cheng Chen 
Update Mechanical, Thermal, Reliability sections Internal 
release 
1/24/2019 
Whitney Zhao 
Siamak Tavallaei 
Add power profiles, power sequence requirement 
Update license information, overview 
Internal 
release 
2/4/2019 
Tiffany Jin 
Whitney Zhao 
Update module drawings 
Update pin list, recommended topologies 
0.8 2/7/2019 
Whitney Zhao Updated some typos, interconnect topologies 
Add LINK_CONFIG table 
0.82  
Tiffany Jin Update ME section 0.83  
Cheng Chen Add liquid cooling concept drawing 0.84  
Whitney Zhao Update license information.  
Update topology port mapping 
Add 156.25Mhz clock for Serdes 
0.85  
Whitney Zhao 
Tiffany Jin 
Cheng Chen 
Update AFC interconnect topology routing 
recommendation to be compatible with HMC and 
FC 
Add management link routing guidance 
Update SerDes pin map 
Update ME drawings; more detail on requirements 
vs recommendations 
Add reference data for the increasing need of 
airflow for OAM cooling as die power increases  
0.90  
 
Whitney Zhao 
Tiffany Jin 
Change SerDes R to 7, update it from X20 to X16 
Add two power reduction GPIO pins PWRRDT#[1:0] 
Add 8-port HCM topology and routing guide 
Update Vref range to 1.5V-3.3V 
Update section 8.6, add channel loss budget detail 
diagrams 
Update OAM_Pin_map to rev1.0: Detail change list 
pls refer to OAM_Pin_map_rev1.0 speadsheet; 
Update OAM_Pin_list to R1.0: detail change list pls 
refer to OAM_Pin_list_Rev1.0 spreadsheet 
Additional details on force/pin data for Mirror 
Mezz 
Add combined FC/HCM topology port mapping and 
routing guide. 
1.0 7/25/2019 



  
  67 
OCP Accelerator Module Design Specification v1.0 
 
More clarification on dimensions, requirements vs 
recommendations 
Add interconnect scale out options 
 